(kicad_pcb
	(version 20260206)
	(generator "pcbnew")
	(generator_version "10.0")
	(general
		(thickness 1.6)
		(legacy_teardrops no)
	)
	(paper "A4")
	(title_block
		(title "Bryce Canyon_IOM_IOC_16318-2_OCP.brd")
		(comment 1 "Bryce Canyon / footprints 1405-1412 of 1605")
	)
	(layers
		(0 "F.Cu" signal "TOP")
		(4 "In1.Cu" signal "L2GND")
		(6 "In2.Cu" signal "L3")
		(8 "In3.Cu" signal "L4VCC")
		(10 "In4.Cu" signal "L5VCC")
		(12 "In5.Cu" signal "L6")
		(14 "In6.Cu" signal "L7GND")
		(2 "B.Cu" signal "BOTTOM")
		(9 "F.Adhes" user "F.Adhesive")
		(11 "B.Adhes" user "B.Adhesive")
		(13 "F.Paste" user "Package Geometry/Pastemask Top")
		(15 "B.Paste" user "Package Geometry/Pastemask Bottom")
		(5 "F.SilkS" user "Ref Des/Silkscreen Top")
		(7 "B.SilkS" user "Ref Des/Silkscreen Bottom")
		(1 "F.Mask" user "Board Geometry/Soldermask Top")
		(3 "B.Mask" user "Board Geometry/Soldermask Bottom")
		(17 "Dwgs.User" user "User.Drawings")
		(19 "Cmts.User" user "User.Comments")
		(21 "Eco1.User" user "User.Eco1")
		(23 "Eco2.User" user "User.Eco2")
		(25 "Edge.Cuts" user "Board Geometry/Outline")
		(27 "Margin" user)
		(31 "F.CrtYd" user "Package Geometry/Place Bound Top")
		(29 "B.CrtYd" user "Package Geometry/Place Bound Bottom")
		(35 "F.Fab" user "Ref Des/Assembly Top")
		(33 "B.Fab" user "Ref Des/Assembly Bottom")
	)
	(footprint ""
		(layer "B.Cu")
		(at 165.959536 -38.416738)
		(property "Reference" "C499"
			(at 0 0 0)
			(layer "B.SilkS")
			(hide yes)
			(effects
				(font
					(size 1.27 1.27)
				)
				(justify mirror)
			)
		)
		(property "Value" "SCD01U16V1KX-GP"
			(at 2.8321 -1.7399 0)
			(unlocked yes)
			(layer "B.Fab")
			(hide yes)
			(effects
				(font
					(size 1.016 1.016)
					(thickness 0.1524)
				)
				(justify mirror)
			)
		)
		(property "Device Type" "C0201H13"
			(at 2.8321 -3.2639 0)
			(unlocked yes)
			(layer "B.Fab")
			(hide yes)
			(effects
				(font
					(size 1.016 1.016)
					(thickness 0.1524)
				)
				(justify mirror)
			)
		)
		(duplicate_pad_numbers_are_jumpers no)
		(fp_rect
			(start 0.2794 0.6477)
			(end -0.2794 -0.6477)
			(stroke
				(width 0)
				(type default)
			)
			(fill no)
			(layer "B.CrtYd")
		)
		(fp_rect
			(start 0.2794 0.6477)
			(end -0.2794 -0.6477)
			(stroke
				(width 0)
				(type default)
			)
			(fill no)
			(layer "B.Fab")
		)
		(pad "1" smd custom
			(at 0 -0.2794 180)
			(size 0.0762 0.0762)
			(layers "B.Cu" "B.Mask" "B.Paste")
			(net "PHY_CON_B_TO_IOC_3_DN")
			(options
				(clearance outline)
				(anchor circle)
			)
			(primitives
				(gr_poly
					(pts
						(arc
							(start 0.1524 0.127)
							(mid 0.137521 0.162921)
							(end 0.1016 0.1778)
						)
						(arc
							(start -0.1016 0.1778)
							(mid -0.137521 0.162921)
							(end -0.1524 0.127)
						)
						(arc
							(start -0.1524 -0.127)
							(mid -0.137521 -0.162921)
							(end -0.1016 -0.1778)
						)
						(arc
							(start 0.1016 -0.1778)
							(mid 0.137521 -0.162921)
							(end 0.1524 -0.127)
						)
					)
					(width 0)
					(fill yes)
				)
			)
		)
		(pad "2" smd custom
			(at 0 0.2794 180)
			(size 0.0762 0.0762)
			(layers "B.Cu" "B.Mask" "B.Paste")
			(net "PHY_CON_B_TO_IOC_3_DN_C")
			(options
				(clearance outline)
				(anchor circle)
			)
			(primitives
				(gr_poly
					(pts
						(arc
							(start 0.1524 0.127)
							(mid 0.137521 0.162921)
							(end 0.1016 0.1778)
						)
						(arc
							(start -0.1016 0.1778)
							(mid -0.137521 0.162921)
							(end -0.1524 0.127)
						)
						(arc
							(start -0.1524 -0.127)
							(mid -0.137521 -0.162921)
							(end -0.1016 -0.1778)
						)
						(arc
							(start 0.1016 -0.1778)
							(mid 0.137521 -0.162921)
							(end 0.1524 -0.127)
						)
					)
					(width 0)
					(fill yes)
				)
			)
		)
	)
	(footprint ""
		(layer "B.Cu")
		(at 52.705 -126.33452 180)
		(property "Reference" "C505"
			(at 0 0 0)
			(layer "B.SilkS")
			(hide yes)
			(effects
				(font
					(size 1.27 1.27)
				)
				(justify mirror)
			)
		)
		(property "Value" "SCD1U16V2KX-3GP"
			(at -1.1811 -2.7051 180)
			(unlocked yes)
			(layer "B.Fab")
			(hide yes)
			(effects
				(font
					(size 1.016 1.016)
					(thickness 0.1524)
				)
				(justify mirror)
			)
		)
		(property "Device Type" "C402H22"
			(at -1.1811 -4.2291 180)
			(unlocked yes)
			(layer "B.Fab")
			(hide yes)
			(effects
				(font
					(size 1.016 1.016)
					(thickness 0.1524)
				)
				(justify mirror)
			)
		)
		(duplicate_pad_numbers_are_jumpers no)
		(fp_rect
			(start 0.4318 0.9525)
			(end -0.4318 -0.9525)
			(stroke
				(width 0)
				(type default)
			)
			(fill no)
			(layer "B.CrtYd")
		)
		(fp_rect
			(start 0.4318 0.9525)
			(end -0.4318 -0.9525)
			(stroke
				(width 0)
				(type default)
			)
			(fill no)
			(layer "B.Fab")
		)
		(pad "1" smd custom
			(at 0 -0.4445)
			(size 0.1524 0.1524)
			(layers "B.Cu" "B.Mask" "B.Paste")
			(net "P3V3_STBY")
			(options
				(clearance outline)
				(anchor circle)
			)
			(primitives
				(gr_poly
					(pts
						(arc
							(start 0.3048 0.2032)
							(mid 0.275042 0.275042)
							(end 0.2032 0.3048)
						)
						(arc
							(start -0.2032 0.3048)
							(mid -0.275042 0.275042)
							(end -0.3048 0.2032)
						)
						(arc
							(start -0.3048 -0.2032)
							(mid -0.275042 -0.275042)
							(end -0.2032 -0.3048)
						)
						(arc
							(start 0.2032 -0.3048)
							(mid 0.275042 -0.275042)
							(end 0.3048 -0.2032)
						)
					)
					(width 0)
					(fill yes)
				)
			)
		)
		(pad "2" smd custom
			(at 0 0.4445)
			(size 0.1524 0.1524)
			(layers "B.Cu" "B.Mask" "B.Paste")
			(net "GND")
			(options
				(clearance outline)
				(anchor circle)
			)
			(primitives
				(gr_poly
					(pts
						(arc
							(start 0.3048 0.2032)
							(mid 0.275042 0.275042)
							(end 0.2032 0.3048)
						)
						(arc
							(start -0.2032 0.3048)
							(mid -0.275042 0.275042)
							(end -0.3048 0.2032)
						)
						(arc
							(start -0.3048 -0.2032)
							(mid -0.275042 -0.275042)
							(end -0.2032 -0.3048)
						)
						(arc
							(start 0.2032 -0.3048)
							(mid 0.275042 -0.275042)
							(end 0.3048 -0.2032)
						)
					)
					(width 0)
					(fill yes)
				)
			)
		)
	)
	(footprint ""
		(layer "B.Cu")
		(at 28.4734 -126.3142 -90)
		(property "Reference" "C508"
			(at 0 0 90)
			(layer "B.SilkS")
			(hide yes)
			(effects
				(font
					(size 1.27 1.27)
				)
				(justify mirror)
			)
		)
		(property "Value" "SCD1U16V2KX-3GP"
			(at -1.1811 -2.7051 270)
			(unlocked yes)
			(layer "B.Fab")
			(hide yes)
			(effects
				(font
					(size 1.016 1.016)
					(thickness 0.1524)
				)
				(justify mirror)
			)
		)
		(property "Device Type" "C402H22"
			(at -1.1811 -4.2291 270)
			(unlocked yes)
			(layer "B.Fab")
			(hide yes)
			(effects
				(font
					(size 1.016 1.016)
					(thickness 0.1524)
				)
				(justify mirror)
			)
		)
		(duplicate_pad_numbers_are_jumpers no)
		(fp_rect
			(start 0.4318 0.9525)
			(end -0.4318 -0.9525)
			(stroke
				(width 0)
				(type default)
			)
			(fill no)
			(layer "B.CrtYd")
		)
		(fp_rect
			(start 0.4318 0.9525)
			(end -0.4318 -0.9525)
			(stroke
				(width 0)
				(type default)
			)
			(fill no)
			(layer "B.Fab")
		)
		(pad "1" smd custom
			(at 0 -0.4445 90)
			(size 0.1524 0.1524)
			(layers "B.Cu" "B.Mask" "B.Paste")
			(net "P3V3_STBY")
			(options
				(clearance outline)
				(anchor circle)
			)
			(primitives
				(gr_poly
					(pts
						(arc
							(start 0.3048 0.2032)
							(mid 0.275042 0.275042)
							(end 0.2032 0.3048)
						)
						(arc
							(start -0.2032 0.3048)
							(mid -0.275042 0.275042)
							(end -0.3048 0.2032)
						)
						(arc
							(start -0.3048 -0.2032)
							(mid -0.275042 -0.275042)
							(end -0.2032 -0.3048)
						)
						(arc
							(start 0.2032 -0.3048)
							(mid 0.275042 -0.275042)
							(end 0.3048 -0.2032)
						)
					)
					(width 0)
					(fill yes)
				)
			)
		)
		(pad "2" smd custom
			(at 0 0.4445 90)
			(size 0.1524 0.1524)
			(layers "B.Cu" "B.Mask" "B.Paste")
			(net "GND")
			(options
				(clearance outline)
				(anchor circle)
			)
			(primitives
				(gr_poly
					(pts
						(arc
							(start 0.3048 0.2032)
							(mid 0.275042 0.275042)
							(end 0.2032 0.3048)
						)
						(arc
							(start -0.2032 0.3048)
							(mid -0.275042 0.275042)
							(end -0.3048 0.2032)
						)
						(arc
							(start -0.3048 -0.2032)
							(mid -0.275042 -0.275042)
							(end -0.2032 -0.3048)
						)
						(arc
							(start 0.2032 -0.3048)
							(mid 0.275042 -0.275042)
							(end 0.3048 -0.2032)
						)
					)
					(width 0)
					(fill yes)
				)
			)
		)
	)
	(footprint ""
		(layer "B.Cu")
		(at 34.404046 -142.938246 180)
		(property "Reference" "C57"
			(at 0 0 0)
			(layer "B.SilkS")
			(hide yes)
			(effects
				(font
					(size 1.27 1.27)
				)
				(justify mirror)
			)
		)
		(property "Value" "SC10U6D3V5KX-4GP"
			(at 0.0762 -6.1214 180)
			(unlocked yes)
			(layer "B.Fab")
			(hide yes)
			(effects
				(font
					(size 1.016 1.016)
					(thickness 0.1524)
				)
				(justify mirror)
			)
		)
		(property "Device Type" "C805H58"
			(at 0.0762 -8.1534 180)
			(unlocked yes)
			(layer "B.Fab")
			(hide yes)
			(effects
				(font
					(size 1.016 1.016)
					(thickness 0.1524)
				)
				(justify mirror)
			)
		)
		(duplicate_pad_numbers_are_jumpers no)
		(fp_line
			(start -0.635 0)
			(end 0.635 0)
			(stroke
				(width 0.508)
				(type default)
			)
			(layer "B.SilkS")
		)
		(fp_rect
			(start 0.9652 1.778)
			(end -0.9652 -1.778)
			(stroke
				(width 0)
				(type default)
			)
			(fill no)
			(layer "B.CrtYd")
		)
		(fp_poly
			(pts
				(xy 0.9652 -1.778) (xy -0.9652 -1.778) (xy -0.9652 1.778) (xy 0.9652 1.778)
			)
			(stroke
				(width 0)
				(type default)
			)
			(fill no)
			(layer "B.Fab")
		)
		(pad "1" smd rect
			(at 0 -0.9652)
			(size 1.397 1.143)
			(layers "B.Cu" "B.Mask" "B.Paste")
			(net "GND")
		)
		(pad "2" smd rect
			(at 0 0.9652)
			(size 1.397 1.143)
			(layers "B.Cu" "B.Mask" "B.Paste")
			(net "P1V2_STBY")
		)
	)
	(footprint ""
		(layer "B.Cu")
		(at 140.843 -18.415 90)
		(property "Reference" "U51"
			(at 0 0 90)
			(layer "B.SilkS")
			(hide yes)
			(effects
				(font
					(size 1.27 1.27)
				)
				(justify mirror)
			)
		)
		(property "Value" "SN74LVC1G08DCKR-GP"
			(at 2.3368 -8.6868 90)
			(unlocked yes)
			(layer "B.Fab")
			(hide yes)
			(effects
				(font
					(size 1.016 1.016)
					(thickness 0.1524)
				)
				(justify mirror)
			)
		)
		(property "Device Type" "SC70-5H44"
			(at 2.3114 -10.414 90)
			(unlocked yes)
			(layer "B.Fab")
			(hide yes)
			(effects
				(font
					(size 1.016 1.016)
					(thickness 0.1524)
				)
				(justify mirror)
			)
		)
		(duplicate_pad_numbers_are_jumpers no)
		(fp_line
			(start -0.6604 -1.8034)
			(end -1.3843 -1.8034)
			(stroke
				(width 0.3302)
				(type default)
			)
			(layer "B.SilkS")
		)
		(fp_line
			(start -1.3843 -1.8034)
			(end -1.3843 -1.1176)
			(stroke
				(width 0.3302)
				(type default)
			)
			(layer "B.SilkS")
		)
		(fp_line
			(start 1.27 -1.7018)
			(end -1.27 -1.7018)
			(stroke
				(width 0.1524)
				(type default)
			)
			(layer "B.SilkS")
		)
		(fp_line
			(start -1.27 -1.7018)
			(end -1.27 1.7018)
			(stroke
				(width 0.1524)
				(type default)
			)
			(layer "B.SilkS")
		)
		(fp_line
			(start 1.27 1.7018)
			(end 1.27 -1.7018)
			(stroke
				(width 0.1524)
				(type default)
			)
			(layer "B.SilkS")
		)
		(fp_line
			(start -1.27 1.7018)
			(end 1.27 1.7018)
			(stroke
				(width 0.1524)
				(type default)
			)
			(layer "B.SilkS")
		)
		(fp_rect
			(start 1.524 1.9558)
			(end -1.524 -1.9558)
			(stroke
				(width 0)
				(type default)
			)
			(fill no)
			(layer "B.CrtYd")
		)
		(fp_poly
			(pts
				(xy 1.524 -1.9558) (xy -1.524 -1.9558) (xy -1.524 1.9558) (xy 1.524 1.9558)
			)
			(stroke
				(width 0)
				(type default)
			)
			(fill no)
			(layer "B.Fab")
		)
		(pad "1" smd rect
			(at -0.65024 -0.8255 270)
			(size 0.4064 1.2192)
			(layers "B.Cu" "B.Mask" "B.Paste")
			(net "BMC_EXT2_LED_Y")
		)
		(pad "2" smd rect
			(at 0 -0.8255 270)
			(size 0.4064 1.2192)
			(layers "B.Cu" "B.Mask" "B.Paste")
			(net "IOC_EXT2_LED_B")
		)
		(pad "3" smd rect
			(at 0.65024 -0.8255 270)
			(size 0.4064 1.2192)
			(layers "B.Cu" "B.Mask" "B.Paste")
			(net "GND")
		)
		(pad "4" smd rect
			(at 0.65024 0.8255 270)
			(size 0.4064 1.2192)
			(layers "B.Cu" "B.Mask" "B.Paste")
			(net "EXT2_LED_BLUE_G_Q27")
		)
		(pad "5" smd rect
			(at -0.65024 0.8255 270)
			(size 0.4064 1.2192)
			(layers "B.Cu" "B.Mask" "B.Paste")
			(net "P1V8")
		)
	)
	(footprint ""
		(layer "B.Cu")
		(at 90.88628 -178.9684 90)
		(property "Reference" "U15"
			(at 0 0 90)
			(layer "B.SilkS")
			(hide yes)
			(effects
				(font
					(size 1.27 1.27)
				)
				(justify mirror)
			)
		)
		(property "Value" "NX3L1G66GW-GP"
			(at 2.3368 -8.6868 90)
			(unlocked yes)
			(layer "B.Fab")
			(hide yes)
			(effects
				(font
					(size 1.016 1.016)
					(thickness 0.1524)
				)
				(justify mirror)
			)
		)
		(property "Device Type" "SC70-5H44"
			(at 2.3114 -10.414 90)
			(unlocked yes)
			(layer "B.Fab")
			(hide yes)
			(effects
				(font
					(size 1.016 1.016)
					(thickness 0.1524)
				)
				(justify mirror)
			)
		)
		(duplicate_pad_numbers_are_jumpers no)
		(fp_line
			(start -0.6604 -1.8034)
			(end -1.3843 -1.8034)
			(stroke
				(width 0.3302)
				(type default)
			)
			(layer "B.SilkS")
		)
		(fp_line
			(start -1.3843 -1.8034)
			(end -1.3843 -1.1176)
			(stroke
				(width 0.3302)
				(type default)
			)
			(layer "B.SilkS")
		)
		(fp_line
			(start 1.27 -1.7018)
			(end -1.27 -1.7018)
			(stroke
				(width 0.1524)
				(type default)
			)
			(layer "B.SilkS")
		)
		(fp_line
			(start -1.27 -1.7018)
			(end -1.27 1.7018)
			(stroke
				(width 0.1524)
				(type default)
			)
			(layer "B.SilkS")
		)
		(fp_line
			(start 1.27 1.7018)
			(end 1.27 -1.7018)
			(stroke
				(width 0.1524)
				(type default)
			)
			(layer "B.SilkS")
		)
		(fp_line
			(start -1.27 1.7018)
			(end 1.27 1.7018)
			(stroke
				(width 0.1524)
				(type default)
			)
			(layer "B.SilkS")
		)
		(fp_rect
			(start 1.524 1.9558)
			(end -1.524 -1.9558)
			(stroke
				(width 0)
				(type default)
			)
			(fill no)
			(layer "B.CrtYd")
		)
		(fp_poly
			(pts
				(xy 1.524 -1.9558) (xy -1.524 -1.9558) (xy -1.524 1.9558) (xy 1.524 1.9558)
			)
			(stroke
				(width 0)
				(type default)
			)
			(fill no)
			(layer "B.Fab")
		)
		(pad "1" smd rect
			(at -0.65024 -0.8255 270)
			(size 0.4064 1.2192)
			(layers "B.Cu" "B.Mask" "B.Paste")
			(net "I2C_BMC_COMP_SDA_R")
		)
		(pad "2" smd rect
			(at 0 -0.8255 270)
			(size 0.4064 1.2192)
			(layers "B.Cu" "B.Mask" "B.Paste")
			(net "I2C_BMC_COMP_SDA_OUT")
		)
		(pad "3" smd rect
			(at 0.65024 -0.8255 270)
			(size 0.4064 1.2192)
			(layers "B.Cu" "B.Mask" "B.Paste")
			(net "GND")
		)
		(pad "4" smd rect
			(at 0.65024 0.8255 270)
			(size 0.4064 1.2192)
			(layers "B.Cu" "B.Mask" "B.Paste")
			(net "COMP_PWR_EN")
		)
		(pad "5" smd rect
			(at -0.65024 0.8255 270)
			(size 0.4064 1.2192)
			(layers "B.Cu" "B.Mask" "B.Paste")
			(net "P3V3_STBY")
		)
	)
	(footprint ""
		(layer "B.Cu")
		(at 46.6344 -161.3662 90)
		(property "Reference" "R324"
			(at 0 0 90)
			(layer "B.SilkS")
			(hide yes)
			(effects
				(font
					(size 1.27 1.27)
				)
				(justify mirror)
			)
		)
		(property "Value" "4K7R2F-GP"
			(at -0.064008 -3.993896 90)
			(unlocked yes)
			(layer "B.Fab")
			(hide yes)
			(effects
				(font
					(size 1.016 1.016)
					(thickness 0.1524)
				)
				(justify mirror)
			)
		)
		(property "Device Type" "R402H16"
			(at -0.064008 -5.517896 90)
			(unlocked yes)
			(layer "B.Fab")
			(hide yes)
			(effects
				(font
					(size 1.016 1.016)
					(thickness 0.1524)
				)
				(justify mirror)
			)
		)
		(duplicate_pad_numbers_are_jumpers no)
		(fp_line
			(start 0.508 -0.9398)
			(end 0.508 0.9398)
			(stroke
				(width 0.1524)
				(type default)
			)
			(layer "B.SilkS")
		)
		(fp_line
			(start -0.508 -0.9398)
			(end 0.508 -0.9398)
			(stroke
				(width 0.1524)
				(type default)
			)
			(layer "B.SilkS")
		)
		(fp_rect
			(start 0.508 0.9398)
			(end -0.508 -0.9398)
			(stroke
				(width 0)
				(type default)
			)
			(fill no)
			(layer "B.CrtYd")
		)
		(fp_rect
			(start 0.508 0.9398)
			(end -0.508 -0.9398)
			(stroke
				(width 0)
				(type default)
			)
			(fill no)
			(layer "B.Fab")
		)
		(pad "1" smd custom
			(at 0 -0.4445 270)
			(size 0.1397 0.1397)
			(layers "B.Cu" "B.Mask" "B.Paste")
			(net "BOARD_REV_2")
			(options
				(clearance outline)
				(anchor circle)
			)
			(primitives
				(gr_poly
					(pts
						(arc
							(start -0.1778 0.2794)
							(mid -0.249642 0.249642)
							(end -0.2794 0.1778)
						)
						(arc
							(start -0.2794 -0.1778)
							(mid -0.249642 -0.249642)
							(end -0.1778 -0.2794)
						)
						(arc
							(start 0.1778 -0.2794)
							(mid 0.249642 -0.249642)
							(end 0.2794 -0.1778)
						)
						(arc
							(start 0.2794 0.1778)
							(mid 0.249642 0.249642)
							(end 0.1778 0.2794)
						)
					)
					(width 0)
					(fill yes)
				)
			)
		)
		(pad "2" smd custom
			(at 0 0.4445 270)
			(size 0.1397 0.1397)
			(layers "B.Cu" "B.Mask" "B.Paste")
			(net "GND")
			(options
				(clearance outline)
				(anchor circle)
			)
			(primitives
				(gr_poly
					(pts
						(arc
							(start -0.1778 0.2794)
							(mid -0.249642 0.249642)
							(end -0.2794 0.1778)
						)
						(arc
							(start -0.2794 -0.1778)
							(mid -0.249642 -0.249642)
							(end -0.1778 -0.2794)
						)
						(arc
							(start 0.1778 -0.2794)
							(mid 0.249642 -0.249642)
							(end 0.2794 -0.1778)
						)
						(arc
							(start 0.2794 0.1778)
							(mid 0.249642 0.249642)
							(end 0.1778 0.2794)
						)
					)
					(width 0)
					(fill yes)
				)
			)
		)
	)
	(footprint ""
		(layer "B.Cu")
		(at 35.862006 -150.758398 180)
		(property "Reference" "C54"
			(at 0 0 0)
			(layer "B.SilkS")
			(hide yes)
			(effects
				(font
					(size 1.27 1.27)
				)
				(justify mirror)
			)
		)
		(property "Value" "SC1U16V3KX-5GP"
			(at 0 -2.8194 180)
			(unlocked yes)
			(layer "B.Fab")
			(hide yes)
			(effects
				(font
					(size 1.016 1.016)
					(thickness 0.1524)
				)
				(justify mirror)
			)
		)
		(property "Device Type" "C603H36"
			(at 0 -4.3434 180)
			(unlocked yes)
			(layer "B.Fab")
			(hide yes)
			(effects
				(font
					(size 1.016 1.016)
					(thickness 0.1524)
				)
				(justify mirror)
			)
		)
		(duplicate_pad_numbers_are_jumpers no)
		(fp_line
			(start -0.508 0)
			(end 0.508 0)
			(stroke
				(width 0.2032)
				(type default)
			)
			(layer "B.SilkS")
		)
		(fp_rect
			(start 0.5842 1.3335)
			(end -0.5842 -1.3335)
			(stroke
				(width 0)
				(type default)
			)
			(fill no)
			(layer "B.CrtYd")
		)
		(fp_rect
			(start 0.5842 1.3335)
			(end -0.5842 -1.3335)
			(stroke
				(width 0)
				(type default)
			)
			(fill no)
			(layer "B.Fab")
		)
		(pad "1" smd custom
			(at 0 -0.762)
			(size 0.2159 0.2159)
			(layers "B.Cu" "B.Mask" "B.Paste")
			(net "DDR_VREF")
			(options
				(clearance outline)
				(anchor circle)
			)
			(primitives
				(gr_poly
					(pts
						(arc
							(start -0.3302 0.4318)
							(mid -0.402042 0.402042)
							(end -0.4318 0.3302)
						)
						(arc
							(start -0.4318 -0.3302)
							(mid -0.402042 -0.402042)
							(end -0.3302 -0.4318)
						)
						(arc
							(start 0.3302 -0.4318)
							(mid 0.402042 -0.402042)
							(end 0.4318 -0.3302)
						)
						(arc
							(start 0.4318 0.3302)
							(mid 0.402042 0.402042)
							(end 0.3302 0.4318)
						)
					)
					(width 0)
					(fill yes)
				)
			)
		)
		(pad "2" smd custom
			(at 0 0.762)
			(size 0.2159 0.2159)
			(layers "B.Cu" "B.Mask" "B.Paste")
			(net "GND")
			(options
				(clearance outline)
				(anchor circle)
			)
			(primitives
				(gr_poly
					(pts
						(arc
							(start -0.3302 0.4318)
							(mid -0.402042 0.402042)
							(end -0.4318 0.3302)
						)
						(arc
							(start -0.4318 -0.3302)
							(mid -0.402042 -0.402042)
							(end -0.3302 -0.4318)
						)
						(arc
							(start 0.3302 -0.4318)
							(mid 0.402042 -0.402042)
							(end 0.4318 -0.3302)
						)
						(arc
							(start 0.4318 0.3302)
							(mid 0.402042 0.402042)
							(end 0.3302 0.4318)
						)
					)
					(width 0)
					(fill yes)
				)
			)
		)
	)
)
